(kicad_pcb
	(version 20241229)
	(generator "pcbnew")
	(generator_version "9.0")
	(general
		(thickness 1.6296)
		(legacy_teardrops no)
	)
	(paper "A3")
	(title_block
		(title "Thunderbolt to 10GbE adapter")
		(date "2026-04-21")
		(rev "1.1.0")
		(company "Antmicro Ltd")
		(comment 1 "www.antmicro.com")
		(comment 9 "footprints 583-587 of 703")
	)
	(layers
		(0 "F.Cu" signal)
		(4 "In1.Cu" signal)
		(6 "In2.Cu" signal)
		(8 "In3.Cu" signal)
		(10 "In4.Cu" signal)
		(12 "In5.Cu" signal)
		(14 "In6.Cu" signal)
		(2 "B.Cu" signal)
		(9 "F.Adhes" user "F.Adhesive")
		(11 "B.Adhes" user "B.Adhesive")
		(13 "F.Paste" user)
		(15 "B.Paste" user)
		(5 "F.SilkS" user "F.Silkscreen")
		(7 "B.SilkS" user "B.Silkscreen")
		(1 "F.Mask" user)
		(3 "B.Mask" user)
		(17 "Dwgs.User" user "User.Drawings")
		(19 "Cmts.User" user "User.Comments")
		(21 "Eco1.User" user "User.Eco1")
		(23 "Eco2.User" user "User.Eco2")
		(25 "Edge.Cuts" user)
		(27 "Margin" user)
		(31 "F.CrtYd" user "F.Courtyard")
		(29 "B.CrtYd" user "B.Courtyard")
		(35 "F.Fab" user)
		(33 "B.Fab" user)
	)
	(footprint "antmicro-footprints:R_0402_1005Metric"
		(layer "B.Cu")
		(at 133.85 131.1 -90)
		(descr "Resistor SMD 0402")
		(tags "resistor SMD 0402")
		(property "Reference" "R5"
			(at -8.35 -19.525001 90)
			(layer "B.SilkS")
			(effects
				(font
					(size 0.7 0.7)
					(thickness 0.15)
				)
				(justify mirror)
			)
		)
		(property "Value" "R_100k_0402"
			(at -1.011843 -1.772047 90)
			(layer "B.Fab")
			(effects
				(font
					(size 0.7 0.7)
					(thickness 0.15)
				)
				(justify left bottom mirror)
			)
		)
		(property "Datasheet" "https://www.bourns.com/docs/product-datasheets/cr.pdf"
			(at 0 0 90)
			(layer "B.Fab")
			(hide yes)
			(effects
				(font
					(size 1.27 1.27)
					(thickness 0.15)
				)
				(justify mirror)
			)
		)
		(property "Description" "SMD Chip Resistor, 100 kohm, ± 1%, 62.5 mW, 0402 [1005 Metric], Thick Film, General Purpose"
			(at 0 0 90)
			(layer "B.Fab")
			(hide yes)
			(effects
				(font
					(size 1.27 1.27)
					(thickness 0.15)
				)
				(justify mirror)
			)
		)
		(property "MPN" "CR0402-FX-1003GLF"
			(at 0 0 270)
			(unlocked yes)
			(layer "B.Fab")
			(hide yes)
			(effects
				(font
					(size 1 1)
					(thickness 0.15)
				)
				(justify mirror)
			)
		)
		(property "Manufacturer" "Bourns"
			(at 0 0 270)
			(unlocked yes)
			(layer "B.Fab")
			(hide yes)
			(effects
				(font
					(size 1 1)
					(thickness 0.15)
				)
				(justify mirror)
			)
		)
		(property "License" "Apache-2.0"
			(at 0 0 270)
			(unlocked yes)
			(layer "B.Fab")
			(hide yes)
			(effects
				(font
					(size 1 1)
					(thickness 0.15)
				)
				(justify mirror)
			)
		)
		(property "Val" "100k"
			(at 0 0 270)
			(unlocked yes)
			(layer "B.Fab")
			(hide yes)
			(effects
				(font
					(size 1 1)
					(thickness 0.15)
				)
				(justify mirror)
			)
		)
		(property "Tolerance" "1%"
			(at 0 0 270)
			(unlocked yes)
			(layer "B.Fab")
			(hide yes)
			(effects
				(font
					(size 1 1)
					(thickness 0.15)
				)
				(justify mirror)
			)
		)
		(property "Author" "Antmicro"
			(at 0 0 270)
			(unlocked yes)
			(layer "B.Fab")
			(hide yes)
			(effects
				(font
					(size 1 1)
					(thickness 0.15)
				)
				(justify mirror)
			)
		)
		(sheetname "/PD and TB DC-DC/")
		(sheetfile "PD_and_TB_DC_DC.kicad_sch")
		(attr smd)
		(fp_rect
			(start -0.925 0.47)
			(end 0.925 -0.47)
			(stroke
				(width 0.05)
				(type default)
			)
			(fill no)
			(layer "B.CrtYd")
		)
		(fp_rect
			(start -0.5 0.25)
			(end 0.5 -0.25)
			(stroke
				(width 0.15)
				(type solid)
			)
			(fill no)
			(layer "B.Fab")
		)
		(fp_text user "Author: Antmicro"
			(at -0.95 -4.169 90)
			(layer "B.Fab")
			(effects
				(font
					(size 0.7 0.7)
					(thickness 0.15)
				)
				(justify left bottom mirror)
			)
		)
		(fp_text user "${REFERENCE}"
			(at -0.95 -3.168 90)
			(layer "B.Fab")
			(effects
				(font
					(size 0.7 0.7)
					(thickness 0.15)
				)
				(justify left bottom mirror)
			)
		)
		(fp_text user "License: Apache-2.0"
			(at -0.95 -5.169 90)
			(layer "B.Fab")
			(effects
				(font
					(size 0.7 0.7)
					(thickness 0.15)
				)
				(justify left bottom mirror)
			)
		)
		(pad "1" smd roundrect
			(at -0.48 0 270)
			(size 0.59 0.64)
			(layers "B.Cu" "B.Mask" "B.Paste")
			(roundrect_rratio 0.25)
			(net 23 "GND")
			(pintype "passive")
		)
		(pad "2" smd roundrect
			(at 0.48 0 270)
			(size 0.59 0.64)
			(layers "B.Cu" "B.Mask" "B.Paste")
			(roundrect_rratio 0.25)
			(net 69 "/PD and TB DC-DC/AUX.+")
			(pintype "passive")
		)
	)
	(footprint "antmicro-footprints:TP_SMD_0.75mm"
		(layer "B.Cu")
		(at 183.75 86.25 180)
		(property "Reference" "TP5"
			(at -0.75 -14.5 270)
			(layer "B.SilkS")
			(effects
				(font
					(size 0.7 0.7)
					(thickness 0.15)
				)
				(justify left bottom mirror)
			)
		)
		(property "Value" "TP_0.75mm_SMD"
			(at 0 -1.2 0)
			(layer "B.Fab")
			(effects
				(font
					(size 0.7 0.7)
					(thickness 0.15)
				)
				(justify left bottom mirror)
			)
		)
		(property "Description" "SMT test point"
			(at 0 0 0)
			(layer "B.Fab")
			(hide yes)
			(effects
				(font
					(size 1.27 1.27)
					(thickness 0.15)
				)
				(justify mirror)
			)
		)
		(property "MPN" ""
			(at 0 0 180)
			(unlocked yes)
			(layer "B.Fab")
			(hide yes)
			(effects
				(font
					(size 1 1)
					(thickness 0.15)
				)
				(justify mirror)
			)
		)
		(property "Manufacturer" ""
			(at 0 0 180)
			(unlocked yes)
			(layer "B.Fab")
			(hide yes)
			(effects
				(font
					(size 1 1)
					(thickness 0.15)
				)
				(justify mirror)
			)
		)
		(property "Author" "Antmicro"
			(at 0 0 180)
			(unlocked yes)
			(layer "B.Fab")
			(hide yes)
			(effects
				(font
					(size 1 1)
					(thickness 0.15)
				)
				(justify mirror)
			)
		)
		(property "License" "Apache-2.0"
			(at 0 0 180)
			(unlocked yes)
			(layer "B.Fab")
			(hide yes)
			(effects
				(font
					(size 1 1)
					(thickness 0.15)
				)
				(justify mirror)
			)
		)
		(sheetname "/X710 DCDC converters/")
		(sheetfile "DCDC_converters_X710.kicad_sch")
		(attr exclude_from_pos_files exclude_from_bom)
		(fp_circle
			(center 0 0)
			(end 0.475 0)
			(stroke
				(width 0.05)
				(type default)
			)
			(fill no)
			(layer "B.CrtYd")
		)
		(fp_text user "Author: Antmicro"
			(at -0.4 -3.901 0)
			(layer "B.Fab")
			(effects
				(font
					(size 0.7 0.7)
					(thickness 0.15)
				)
				(justify left bottom mirror)
			)
		)
		(fp_text user "License: Apache-2.0"
			(at -0.4 -5.101 0)
			(layer "B.Fab")
			(effects
				(font
					(size 0.7 0.7)
					(thickness 0.15)
				)
				(justify left bottom mirror)
			)
		)
		(fp_text user "${REFERENCE}"
			(at -0.4 -2.7 0)
			(layer "B.Fab")
			(effects
				(font
					(size 0.7 0.7)
					(thickness 0.15)
				)
				(justify left bottom mirror)
			)
		)
		(pad "1" smd circle
			(at 0 0 180)
			(size 0.75 0.75)
			(layers "B.Cu" "B.Mask")
			(net 23 "GND")
			(pinfunction "1")
			(pintype "passive")
		)
	)
	(footprint "antmicro-footprints:C_0402_1005Metric"
		(layer "B.Cu")
		(at 145.631866 81.260117 180)
		(descr "Capacitor SMD 0402")
		(tags "capacitor SMD 0402")
		(property "Reference" "C255"
			(at -17.768134 -9.464883 0)
			(layer "B.SilkS")
			(effects
				(font
					(size 0.7 0.7)
					(thickness 0.15)
				)
				(justify mirror)
			)
		)
		(property "Value" "C_1u_25V_0402"
			(at -1.022927 -2.155213 0)
			(layer "B.Fab")
			(effects
				(font
					(size 0.7 0.7)
					(thickness 0.15)
				)
				(justify left bottom mirror)
			)
		)
		(property "Datasheet" "https://www.murata.com/products/productdetail?partno=GRM155R61E105KE11%23"
			(at 0 0 0)
			(layer "B.Fab")
			(hide yes)
			(effects
				(font
					(size 1.27 1.27)
					(thickness 0.15)
				)
				(justify mirror)
			)
		)
		(property "Description" "SMD Multilayer Ceramic Capacitor, 1 µF, 25 V, 0402 [1005 Metric], ± 10%, X5R, GRM Series"
			(at 0 0 0)
			(layer "B.Fab")
			(hide yes)
			(effects
				(font
					(size 1.27 1.27)
					(thickness 0.15)
				)
				(justify mirror)
			)
		)
		(property "MPN" "GRM155R61E105KE11J"
			(at 0 0 180)
			(unlocked yes)
			(layer "B.Fab")
			(hide yes)
			(effects
				(font
					(size 1 1)
					(thickness 0.15)
				)
				(justify mirror)
			)
		)
		(property "Manufacturer" "Murata"
			(at 0 0 180)
			(unlocked yes)
			(layer "B.Fab")
			(hide yes)
			(effects
				(font
					(size 1 1)
					(thickness 0.15)
				)
				(justify mirror)
			)
		)
		(property "License" "Apache-2.0"
			(at 0 0 180)
			(unlocked yes)
			(layer "B.Fab")
			(hide yes)
			(effects
				(font
					(size 1 1)
					(thickness 0.15)
				)
				(justify mirror)
			)
		)
		(property "Author" "Antmicro"
			(at 0 0 180)
			(unlocked yes)
			(layer "B.Fab")
			(hide yes)
			(effects
				(font
					(size 1 1)
					(thickness 0.15)
				)
				(justify mirror)
			)
		)
		(property "Val" "1u"
			(at 0 0 180)
			(unlocked yes)
			(layer "B.Fab")
			(hide yes)
			(effects
				(font
					(size 1 1)
					(thickness 0.15)
				)
				(justify mirror)
			)
		)
		(property "Voltage" "25V"
			(at 0 0 180)
			(unlocked yes)
			(layer "B.Fab")
			(hide yes)
			(effects
				(font
					(size 1 1)
					(thickness 0.15)
				)
				(justify mirror)
			)
		)
		(property "Dielectric" "X5R"
			(at 0 0 180)
			(unlocked yes)
			(layer "B.Fab")
			(hide yes)
			(effects
				(font
					(size 1 1)
					(thickness 0.15)
				)
				(justify mirror)
			)
		)
		(sheetname "/X710-AT2 power/")
		(sheetfile "x710-at2-power.kicad_sch")
		(attr smd)
		(fp_rect
			(start -0.925 0.47)
			(end 0.925 -0.47)
			(stroke
				(width 0.05)
				(type default)
			)
			(fill no)
			(layer "B.CrtYd")
		)
		(fp_line
			(start 0.504 0.25)
			(end 0.504 -0.248)
			(stroke
				(width 0.15)
				(type solid)
			)
			(layer "B.Fab")
		)
		(fp_line
			(start 0.504 -0.248)
			(end -0.494 -0.248)
			(stroke
				(width 0.15)
				(type solid)
			)
			(layer "B.Fab")
		)
		(fp_line
			(start -0.494 0.25)
			(end 0.504 0.25)
			(stroke
				(width 0.15)
				(type solid)
			)
			(layer "B.Fab")
		)
		(fp_line
			(start -0.494 -0.248)
			(end -0.494 0.25)
			(stroke
				(width 0.15)
				(type solid)
			)
			(layer "B.Fab")
		)
		(fp_text user "Author: Antmicro"
			(at -0.939 -3.399 0)
			(layer "B.Fab")
			(effects
				(font
					(size 0.7 0.7)
					(thickness 0.15)
				)
				(justify left bottom mirror)
			)
		)
		(fp_text user "${REFERENCE}"
			(at -0.939 -4.599 0)
			(layer "B.Fab")
			(effects
				(font
					(size 0.7 0.7)
					(thickness 0.15)
				)
				(justify left bottom mirror)
			)
		)
		(fp_text user "License: Apache-2.0"
			(at -0.939 -5.799 0)
			(layer "B.Fab")
			(effects
				(font
					(size 0.7 0.7)
					(thickness 0.15)
				)
				(justify left bottom mirror)
			)
		)
		(pad "1" smd roundrect
			(at -0.48 0 180)
			(size 0.59 0.64)
			(layers "B.Cu" "B.Mask" "B.Paste")
			(roundrect_rratio 0.25)
			(net 23 "GND")
			(pintype "passive")
		)
		(pad "2" smd roundrect
			(at 0.48 0 180)
			(size 0.59 0.64)
			(layers "B.Cu" "B.Mask" "B.Paste")
			(roundrect_rratio 0.25)
			(net 1 "VCCA")
			(pintype "passive")
		)
	)
	(footprint "antmicro-footprints:C_0402_1005Metric"
		(layer "B.Cu")
		(at 145.631866 75.260117 180)
		(descr "Capacitor SMD 0402")
		(tags "capacitor SMD 0402")
		(property "Reference" "C213"
			(at -17.768134 -9.464883 0)
			(layer "B.SilkS")
			(effects
				(font
					(size 0.7 0.7)
					(thickness 0.15)
				)
				(justify mirror)
			)
		)
		(property "Value" "C_1u_25V_0402"
			(at -1.022927 -2.155213 0)
			(layer "B.Fab")
			(effects
				(font
					(size 0.7 0.7)
					(thickness 0.15)
				)
				(justify left bottom mirror)
			)
		)
		(property "Datasheet" "https://www.murata.com/products/productdetail?partno=GRM155R61E105KE11%23"
			(at 0 0 0)
			(layer "B.Fab")
			(hide yes)
			(effects
				(font
					(size 1.27 1.27)
					(thickness 0.15)
				)
				(justify mirror)
			)
		)
		(property "Description" "SMD Multilayer Ceramic Capacitor, 1 µF, 25 V, 0402 [1005 Metric], ± 10%, X5R, GRM Series"
			(at 0 0 0)
			(layer "B.Fab")
			(hide yes)
			(effects
				(font
					(size 1.27 1.27)
					(thickness 0.15)
				)
				(justify mirror)
			)
		)
		(property "MPN" "GRM155R61E105KE11J"
			(at 0 0 180)
			(unlocked yes)
			(layer "B.Fab")
			(hide yes)
			(effects
				(font
					(size 1 1)
					(thickness 0.15)
				)
				(justify mirror)
			)
		)
		(property "Manufacturer" "Murata"
			(at 0 0 180)
			(unlocked yes)
			(layer "B.Fab")
			(hide yes)
			(effects
				(font
					(size 1 1)
					(thickness 0.15)
				)
				(justify mirror)
			)
		)
		(property "License" "Apache-2.0"
			(at 0 0 180)
			(unlocked yes)
			(layer "B.Fab")
			(hide yes)
			(effects
				(font
					(size 1 1)
					(thickness 0.15)
				)
				(justify mirror)
			)
		)
		(property "Author" "Antmicro"
			(at 0 0 180)
			(unlocked yes)
			(layer "B.Fab")
			(hide yes)
			(effects
				(font
					(size 1 1)
					(thickness 0.15)
				)
				(justify mirror)
			)
		)
		(property "Val" "1u"
			(at 0 0 180)
			(unlocked yes)
			(layer "B.Fab")
			(hide yes)
			(effects
				(font
					(size 1 1)
					(thickness 0.15)
				)
				(justify mirror)
			)
		)
		(property "Voltage" "25V"
			(at 0 0 180)
			(unlocked yes)
			(layer "B.Fab")
			(hide yes)
			(effects
				(font
					(size 1 1)
					(thickness 0.15)
				)
				(justify mirror)
			)
		)
		(property "Dielectric" "X5R"
			(at 0 0 180)
			(unlocked yes)
			(layer "B.Fab")
			(hide yes)
			(effects
				(font
					(size 1 1)
					(thickness 0.15)
				)
				(justify mirror)
			)
		)
		(sheetname "/X710-AT2 power/")
		(sheetfile "x710-at2-power.kicad_sch")
		(attr smd)
		(fp_rect
			(start -0.925 0.47)
			(end 0.925 -0.47)
			(stroke
				(width 0.05)
				(type default)
			)
			(fill no)
			(layer "B.CrtYd")
		)
		(fp_line
			(start 0.504 0.25)
			(end 0.504 -0.248)
			(stroke
				(width 0.15)
				(type solid)
			)
			(layer "B.Fab")
		)
		(fp_line
			(start 0.504 -0.248)
			(end -0.494 -0.248)
			(stroke
				(width 0.15)
				(type solid)
			)
			(layer "B.Fab")
		)
		(fp_line
			(start -0.494 0.25)
			(end 0.504 0.25)
			(stroke
				(width 0.15)
				(type solid)
			)
			(layer "B.Fab")
		)
		(fp_line
			(start -0.494 -0.248)
			(end -0.494 0.25)
			(stroke
				(width 0.15)
				(type solid)
			)
			(layer "B.Fab")
		)
		(fp_text user "${REFERENCE}"
			(at -0.939 -4.599 0)
			(layer "B.Fab")
			(effects
				(font
					(size 0.7 0.7)
					(thickness 0.15)
				)
				(justify left bottom mirror)
			)
		)
		(fp_text user "Author: Antmicro"
			(at -0.939 -3.399 0)
			(layer "B.Fab")
			(effects
				(font
					(size 0.7 0.7)
					(thickness 0.15)
				)
				(justify left bottom mirror)
			)
		)
		(fp_text user "License: Apache-2.0"
			(at -0.939 -5.799 0)
			(layer "B.Fab")
			(effects
				(font
					(size 0.7 0.7)
					(thickness 0.15)
				)
				(justify left bottom mirror)
			)
		)
		(pad "1" smd roundrect
			(at -0.48 0 180)
			(size 0.59 0.64)
			(layers "B.Cu" "B.Mask" "B.Paste")
			(roundrect_rratio 0.25)
			(net 23 "GND")
			(pintype "passive")
		)
		(pad "2" smd roundrect
			(at 0.48 0 180)
			(size 0.59 0.64)
			(layers "B.Cu" "B.Mask" "B.Paste")
			(roundrect_rratio 0.25)
			(net 9 "VCCD")
			(pintype "passive")
		)
	)
	(footprint "antmicro-footprints:C_0402_1005Metric"
		(layer "B.Cu")
		(at 154.261866 86.265117 180)
		(descr "Capacitor SMD 0402")
		(tags "capacitor SMD 0402")
		(property "Reference" "C201"
			(at -17.938134 -9.464883 0)
			(layer "B.SilkS")
			(effects
				(font
					(size 0.7 0.7)
					(thickness 0.15)
				)
				(justify mirror)
			)
		)
		(property "Value" "C_1u_25V_0402"
			(at -1.022927 -2.155213 0)
			(layer "B.Fab")
			(effects
				(font
					(size 0.7 0.7)
					(thickness 0.15)
				)
				(justify left bottom mirror)
			)
		)
		(property "Datasheet" "https://www.murata.com/products/productdetail?partno=GRM155R61E105KE11%23"
			(at 0 0 0)
			(layer "B.Fab")
			(hide yes)
			(effects
				(font
					(size 1.27 1.27)
					(thickness 0.15)
				)
				(justify mirror)
			)
		)
		(property "Description" "SMD Multilayer Ceramic Capacitor, 1 µF, 25 V, 0402 [1005 Metric], ± 10%, X5R, GRM Series"
			(at 0 0 0)
			(layer "B.Fab")
			(hide yes)
			(effects
				(font
					(size 1.27 1.27)
					(thickness 0.15)
				)
				(justify mirror)
			)
		)
		(property "MPN" "GRM155R61E105KE11J"
			(at 0 0 180)
			(unlocked yes)
			(layer "B.Fab")
			(hide yes)
			(effects
				(font
					(size 1 1)
					(thickness 0.15)
				)
				(justify mirror)
			)
		)
		(property "Manufacturer" "Murata"
			(at 0 0 180)
			(unlocked yes)
			(layer "B.Fab")
			(hide yes)
			(effects
				(font
					(size 1 1)
					(thickness 0.15)
				)
				(justify mirror)
			)
		)
		(property "License" "Apache-2.0"
			(at 0 0 180)
			(unlocked yes)
			(layer "B.Fab")
			(hide yes)
			(effects
				(font
					(size 1 1)
					(thickness 0.15)
				)
				(justify mirror)
			)
		)
		(property "Author" "Antmicro"
			(at 0 0 180)
			(unlocked yes)
			(layer "B.Fab")
			(hide yes)
			(effects
				(font
					(size 1 1)
					(thickness 0.15)
				)
				(justify mirror)
			)
		)
		(property "Val" "1u"
			(at 0 0 180)
			(unlocked yes)
			(layer "B.Fab")
			(hide yes)
			(effects
				(font
					(size 1 1)
					(thickness 0.15)
				)
				(justify mirror)
			)
		)
		(property "Voltage" "25V"
			(at 0 0 180)
			(unlocked yes)
			(layer "B.Fab")
			(hide yes)
			(effects
				(font
					(size 1 1)
					(thickness 0.15)
				)
				(justify mirror)
			)
		)
		(property "Dielectric" "X5R"
			(at 0 0 180)
			(unlocked yes)
			(layer "B.Fab")
			(hide yes)
			(effects
				(font
					(size 1 1)
					(thickness 0.15)
				)
				(justify mirror)
			)
		)
		(sheetname "/X710-AT2 power/")
		(sheetfile "x710-at2-power.kicad_sch")
		(attr smd)
		(fp_rect
			(start -0.925 0.47)
			(end 0.925 -0.47)
			(stroke
				(width 0.05)
				(type default)
			)
			(fill no)
			(layer "B.CrtYd")
		)
		(fp_line
			(start 0.504 0.25)
			(end 0.504 -0.248)
			(stroke
				(width 0.15)
				(type solid)
			)
			(layer "B.Fab")
		)
		(fp_line
			(start 0.504 -0.248)
			(end -0.494 -0.248)
			(stroke
				(width 0.15)
				(type solid)
			)
			(layer "B.Fab")
		)
		(fp_line
			(start -0.494 0.25)
			(end 0.504 0.25)
			(stroke
				(width 0.15)
				(type solid)
			)
			(layer "B.Fab")
		)
		(fp_line
			(start -0.494 -0.248)
			(end -0.494 0.25)
			(stroke
				(width 0.15)
				(type solid)
			)
			(layer "B.Fab")
		)
		(fp_text user "License: Apache-2.0"
			(at -0.939 -5.799 0)
			(layer "B.Fab")
			(effects
				(font
					(size 0.7 0.7)
					(thickness 0.15)
				)
				(justify left bottom mirror)
			)
		)
		(fp_text user "${REFERENCE}"
			(at -0.939 -4.599 0)
			(layer "B.Fab")
			(effects
				(font
					(size 0.7 0.7)
					(thickness 0.15)
				)
				(justify left bottom mirror)
			)
		)
		(fp_text user "Author: Antmicro"
			(at -0.939 -3.399 0)
			(layer "B.Fab")
			(effects
				(font
					(size 0.7 0.7)
					(thickness 0.15)
				)
				(justify left bottom mirror)
			)
		)
		(pad "1" smd roundrect
			(at -0.48 0 180)
			(size 0.59 0.64)
			(layers "B.Cu" "B.Mask" "B.Paste")
			(roundrect_rratio 0.25)
			(net 23 "GND")
			(pintype "passive")
		)
		(pad "2" smd roundrect
			(at 0.48 0 180)
			(size 0.59 0.64)
			(layers "B.Cu" "B.Mask" "B.Paste")
			(roundrect_rratio 0.25)
			(net 12 "XFI_VDD")
			(pintype "passive")
		)
	)
)
